(kicad_pcb
	(version 20260206)
	(generator "pcbnew")
	(generator_version "10.0")
	(general
		(thickness 1.6)
		(legacy_teardrops no)
	)
	(paper "A4")
	(title_block
		(title "Bryce Canyon_IOM_M2_16342-2_OCP.brd")
		(comment 1 "Bryce Canyon / footprints 529-536 of 1146")
	)
	(layers
		(0 "F.Cu" signal "TOP")
		(4 "In1.Cu" signal "L2GND")
		(6 "In2.Cu" signal "L3")
		(8 "In3.Cu" signal "L4VCC")
		(10 "In4.Cu" signal "L5VCC")
		(12 "In5.Cu" signal "L6")
		(14 "In6.Cu" signal "L7GND")
		(2 "B.Cu" signal "BOTTOM")
		(9 "F.Adhes" user "F.Adhesive")
		(11 "B.Adhes" user "B.Adhesive")
		(13 "F.Paste" user "Package Geometry/Pastemask Top")
		(15 "B.Paste" user "Package Geometry/Pastemask Bottom")
		(5 "F.SilkS" user "Ref Des/Silkscreen Top")
		(7 "B.SilkS" user "Ref Des/Silkscreen Bottom")
		(1 "F.Mask" user "Board Geometry/Soldermask Top")
		(3 "B.Mask" user "Board Geometry/Soldermask Bottom")
		(17 "Dwgs.User" user "User.Drawings")
		(19 "Cmts.User" user "User.Comments")
		(21 "Eco1.User" user "User.Eco1")
		(23 "Eco2.User" user "User.Eco2")
		(25 "Edge.Cuts" user "Board Geometry/Outline")
		(27 "Margin" user)
		(31 "F.CrtYd" user "Package Geometry/Place Bound Top")
		(29 "B.CrtYd" user "Package Geometry/Place Bound Bottom")
		(35 "F.Fab" user "Ref Des/Assembly Top")
		(33 "B.Fab" user "Ref Des/Assembly Bottom")
	)
	(footprint ""
		(layer "F.Cu")
		(at 34.531046 -152.161748 -90)
		(property "Reference" "R333"
			(at 0 0 270)
			(layer "F.SilkS")
			(hide yes)
			(effects
				(font
					(size 1.27 1.27)
				)
			)
		)
		(property "Value" "0R2J-2-GP"
			(at 0.064008 -3.993896 270)
			(unlocked yes)
			(layer "F.Fab")
			(hide yes)
			(effects
				(font
					(size 1.016 1.016)
					(thickness 0.1524)
				)
			)
		)
		(property "Device Type" "R402H16"
			(at 0.064008 -5.517896 270)
			(unlocked yes)
			(layer "F.Fab")
			(hide yes)
			(effects
				(font
					(size 1.016 1.016)
					(thickness 0.1524)
				)
			)
		)
		(duplicate_pad_numbers_are_jumpers no)
		(fp_line
			(start -0.508 -0.9398)
			(end -0.508 0.9398)
			(stroke
				(width 0.1524)
				(type default)
			)
			(layer "F.SilkS")
		)
		(fp_line
			(start 0.508 -0.9398)
			(end -0.508 -0.9398)
			(stroke
				(width 0.1524)
				(type default)
			)
			(layer "F.SilkS")
		)
		(fp_rect
			(start -0.508 0.9398)
			(end 0.508 -0.9398)
			(stroke
				(width 0)
				(type default)
			)
			(fill no)
			(layer "F.CrtYd")
		)
		(fp_rect
			(start -0.508 0.9398)
			(end 0.508 -0.9398)
			(stroke
				(width 0)
				(type default)
			)
			(fill no)
			(layer "F.Fab")
		)
		(pad "1" smd custom
			(at 0 -0.4445 270)
			(size 0.1397 0.1397)
			(layers "F.Cu" "F.Mask" "F.Paste")
			(net "THROTTLE_N")
			(options
				(clearance outline)
				(anchor circle)
			)
			(primitives
				(gr_poly
					(pts
						(arc
							(start -0.1778 -0.2794)
							(mid -0.249642 -0.249642)
							(end -0.2794 -0.1778)
						)
						(arc
							(start -0.2794 0.1778)
							(mid -0.249642 0.249642)
							(end -0.1778 0.2794)
						)
						(arc
							(start 0.1778 0.2794)
							(mid 0.249642 0.249642)
							(end 0.2794 0.1778)
						)
						(arc
							(start 0.2794 -0.1778)
							(mid 0.249642 -0.249642)
							(end 0.1778 -0.2794)
						)
					)
					(width 0)
					(fill yes)
				)
			)
		)
		(pad "2" smd custom
			(at 0 0.4445 270)
			(size 0.1397 0.1397)
			(layers "F.Cu" "F.Mask" "F.Paste")
			(net "COMP_FAST_THROTTLE_N")
			(options
				(clearance outline)
				(anchor circle)
			)
			(primitives
				(gr_poly
					(pts
						(arc
							(start -0.1778 -0.2794)
							(mid -0.249642 -0.249642)
							(end -0.2794 -0.1778)
						)
						(arc
							(start -0.2794 0.1778)
							(mid -0.249642 0.249642)
							(end -0.1778 0.2794)
						)
						(arc
							(start 0.1778 0.2794)
							(mid 0.249642 0.249642)
							(end 0.2794 0.1778)
						)
						(arc
							(start 0.2794 -0.1778)
							(mid 0.249642 -0.249642)
							(end 0.1778 -0.2794)
						)
					)
					(width 0)
					(fill yes)
				)
			)
		)
	)
	(footprint ""
		(layer "F.Cu")
		(at 212.830664 -89.386156 -90)
		(property "Reference" "R839"
			(at 0 0 270)
			(layer "F.SilkS")
			(hide yes)
			(effects
				(font
					(size 1.27 1.27)
				)
			)
		)
		(property "Value" "10KR2F-2-GP"
			(at 0.064008 -3.993896 270)
			(unlocked yes)
			(layer "F.Fab")
			(hide yes)
			(effects
				(font
					(size 1.016 1.016)
					(thickness 0.1524)
				)
			)
		)
		(property "Device Type" "R402H16"
			(at 0.064008 -5.517896 270)
			(unlocked yes)
			(layer "F.Fab")
			(hide yes)
			(effects
				(font
					(size 1.016 1.016)
					(thickness 0.1524)
				)
			)
		)
		(duplicate_pad_numbers_are_jumpers no)
		(fp_line
			(start -0.508 -0.9398)
			(end -0.508 0.9398)
			(stroke
				(width 0.1524)
				(type default)
			)
			(layer "F.SilkS")
		)
		(fp_line
			(start 0.508 -0.9398)
			(end -0.508 -0.9398)
			(stroke
				(width 0.1524)
				(type default)
			)
			(layer "F.SilkS")
		)
		(fp_rect
			(start -0.508 0.9398)
			(end 0.508 -0.9398)
			(stroke
				(width 0)
				(type default)
			)
			(fill no)
			(layer "F.CrtYd")
		)
		(fp_rect
			(start -0.508 0.9398)
			(end 0.508 -0.9398)
			(stroke
				(width 0)
				(type default)
			)
			(fill no)
			(layer "F.Fab")
		)
		(pad "1" smd custom
			(at 0 -0.4445 270)
			(size 0.1397 0.1397)
			(layers "F.Cu" "F.Mask" "F.Paste")
			(net "GND")
			(options
				(clearance outline)
				(anchor circle)
			)
			(primitives
				(gr_poly
					(pts
						(arc
							(start -0.1778 -0.2794)
							(mid -0.249642 -0.249642)
							(end -0.2794 -0.1778)
						)
						(arc
							(start -0.2794 0.1778)
							(mid -0.249642 0.249642)
							(end -0.1778 0.2794)
						)
						(arc
							(start 0.1778 0.2794)
							(mid 0.249642 0.249642)
							(end 0.2794 0.1778)
						)
						(arc
							(start 0.2794 -0.1778)
							(mid 0.249642 -0.249642)
							(end 0.1778 -0.2794)
						)
					)
					(width 0)
					(fill yes)
				)
			)
		)
		(pad "2" smd custom
			(at 0 0.4445 270)
			(size 0.1397 0.1397)
			(layers "F.Cu" "F.Mask" "F.Paste")
			(net "P3V3_PG")
			(options
				(clearance outline)
				(anchor circle)
			)
			(primitives
				(gr_poly
					(pts
						(arc
							(start -0.1778 -0.2794)
							(mid -0.249642 -0.249642)
							(end -0.2794 -0.1778)
						)
						(arc
							(start -0.2794 0.1778)
							(mid -0.249642 0.249642)
							(end -0.1778 0.2794)
						)
						(arc
							(start 0.1778 0.2794)
							(mid 0.249642 0.249642)
							(end 0.2794 0.1778)
						)
						(arc
							(start 0.2794 -0.1778)
							(mid 0.249642 -0.249642)
							(end 0.1778 -0.2794)
						)
					)
					(width 0)
					(fill yes)
				)
			)
		)
	)
	(footprint ""
		(layer "F.Cu")
		(at 89.52992 -148.809456 180)
		(property "Reference" "R33"
			(at 0 0 180)
			(layer "F.SilkS")
			(hide yes)
			(effects
				(font
					(size 1.27 1.27)
				)
			)
		)
		(property "Value" "4K7R2F-GP"
			(at 0.064008 -3.993896 180)
			(unlocked yes)
			(layer "F.Fab")
			(hide yes)
			(effects
				(font
					(size 1.016 1.016)
					(thickness 0.1524)
				)
			)
		)
		(property "Device Type" "R402H16"
			(at 0.064008 -5.517896 180)
			(unlocked yes)
			(layer "F.Fab")
			(hide yes)
			(effects
				(font
					(size 1.016 1.016)
					(thickness 0.1524)
				)
			)
		)
		(duplicate_pad_numbers_are_jumpers no)
		(fp_line
			(start 0.508 -0.9398)
			(end -0.508 -0.9398)
			(stroke
				(width 0.1524)
				(type default)
			)
			(layer "F.SilkS")
		)
		(fp_line
			(start -0.508 -0.9398)
			(end -0.508 0.9398)
			(stroke
				(width 0.1524)
				(type default)
			)
			(layer "F.SilkS")
		)
		(fp_rect
			(start -0.508 0.9398)
			(end 0.508 -0.9398)
			(stroke
				(width 0)
				(type default)
			)
			(fill no)
			(layer "F.CrtYd")
		)
		(fp_rect
			(start -0.508 0.9398)
			(end 0.508 -0.9398)
			(stroke
				(width 0)
				(type default)
			)
			(fill no)
			(layer "F.Fab")
		)
		(pad "1" smd custom
			(at 0 -0.4445 180)
			(size 0.1397 0.1397)
			(layers "F.Cu" "F.Mask" "F.Paste")
			(net "P3V3_STBY")
			(options
				(clearance outline)
				(anchor circle)
			)
			(primitives
				(gr_poly
					(pts
						(arc
							(start -0.1778 -0.2794)
							(mid -0.249642 -0.249642)
							(end -0.2794 -0.1778)
						)
						(arc
							(start -0.2794 0.1778)
							(mid -0.249642 0.249642)
							(end -0.1778 0.2794)
						)
						(arc
							(start 0.1778 0.2794)
							(mid 0.249642 0.249642)
							(end 0.2794 0.1778)
						)
						(arc
							(start 0.2794 -0.1778)
							(mid 0.249642 -0.249642)
							(end 0.1778 -0.2794)
						)
					)
					(width 0)
					(fill yes)
				)
			)
		)
		(pad "2" smd custom
			(at 0 0.4445 180)
			(size 0.1397 0.1397)
			(layers "F.Cu" "F.Mask" "F.Paste")
			(net "USB_EN_1")
			(options
				(clearance outline)
				(anchor circle)
			)
			(primitives
				(gr_poly
					(pts
						(arc
							(start -0.1778 -0.2794)
							(mid -0.249642 -0.249642)
							(end -0.2794 -0.1778)
						)
						(arc
							(start -0.2794 0.1778)
							(mid -0.249642 0.249642)
							(end -0.1778 0.2794)
						)
						(arc
							(start 0.1778 0.2794)
							(mid 0.249642 0.249642)
							(end 0.2794 0.1778)
						)
						(arc
							(start 0.2794 -0.1778)
							(mid 0.249642 -0.249642)
							(end 0.1778 -0.2794)
						)
					)
					(width 0)
					(fill yes)
				)
			)
		)
	)
	(footprint ""
		(layer "F.Cu")
		(at 195.453 -140.716 -135)
		(property "Reference" "VIA56"
			(at 0 0 225)
			(layer "F.SilkS")
			(hide yes)
			(effects
				(font
					(size 1.27 1.27)
				)
			)
		)
		(property "Value" "85OHM-8L-1D6MM-L16L18-GP"
			(at 4.064105 0.609655 225)
			(unlocked yes)
			(layer "F.Fab")
			(hide yes)
			(effects
				(font
					(size 1.016 1.016)
					(thickness 0.1524)
				)
			)
		)
		(property "Device Type" "VIA-PCIE-4P-368076"
			(at 4.064105 -0.914474 225)
			(unlocked yes)
			(layer "F.Fab")
			(hide yes)
			(effects
				(font
					(size 1.016 1.016)
					(thickness 0.1524)
				)
			)
		)
		(duplicate_pad_numbers_are_jumpers no)
		(fp_poly
			(pts
				(xy -1.841491 -0.381057) (xy 1.841509 -0.381058) (xy 1.841508 0.380942) (xy -1.841491 0.380942)
			)
			(stroke
				(width 0)
				(type default)
			)
			(fill no)
			(layer "F.CrtYd")
		)
		(fp_poly
			(pts
				(xy -1.841491 -0.381057) (xy 1.841509 -0.381058) (xy 1.841508 0.380942) (xy -1.841491 0.380942)
			)
			(stroke
				(width 0)
				(type default)
			)
			(fill no)
			(layer "F.Fab")
		)
		(pad "1" thru_hole circle
			(at -1.460499 0 225)
			(size 0.508 0.508)
			(drill 0.254)
			(layers "*.Cu" "*.Mask")
			(remove_unused_layers no)
			(net "GND")
			(clearance 0.127)
			(thermal_gap 0.127)
		)
		(pad "2" thru_hole circle
			(at -0.4445 0 225)
			(size 0.508 0.508)
			(drill 0.254)
			(layers "*.Cu" "*.Mask")
			(remove_unused_layers no)
			(net "PCIE_COMP_TO_IOM_11_DP")
			(clearance 0.127)
			(thermal_gap 0.127)
		)
		(pad "3" thru_hole circle
			(at 0.4445 0 225)
			(size 0.508 0.508)
			(drill 0.254)
			(layers "*.Cu" "*.Mask")
			(remove_unused_layers no)
			(net "PCIE_COMP_TO_IOM_11_DN")
			(clearance 0.127)
			(thermal_gap 0.127)
		)
		(pad "4" thru_hole circle
			(at 1.460499 0 225)
			(size 0.508 0.508)
			(drill 0.254)
			(layers "*.Cu" "*.Mask")
			(remove_unused_layers no)
			(net "GND")
			(clearance 0.127)
			(thermal_gap 0.127)
		)
	)
	(footprint ""
		(layer "F.Cu")
		(at 42.5196 -157.0482)
		(property "Reference" "TP187"
			(at 0 0 0)
			(layer "F.SilkS")
			(hide yes)
			(effects
				(font
					(size 1.27 1.27)
				)
			)
		)
		(property "Value" "TPAD28-2-GP"
			(at -0.0127 -1.6637 0)
			(unlocked yes)
			(layer "F.Fab")
			(hide yes)
			(effects
				(font
					(size 1.016 1.016)
					(thickness 0.1524)
				)
			)
		)
		(property "Device Type" "TPAD28"
			(at -0.0127 -3.1877 0)
			(unlocked yes)
			(layer "F.Fab")
			(hide yes)
			(effects
				(font
					(size 1.016 1.016)
					(thickness 0.1524)
				)
			)
		)
		(duplicate_pad_numbers_are_jumpers no)
		(fp_poly
			(pts
				(arc
					(start 0.3556 0)
					(mid -0.3556 0)
					(end 0.3556 0)
				)
			)
			(stroke
				(width 0)
				(type default)
			)
			(fill no)
			(layer "F.CrtYd")
		)
		(fp_poly
			(pts
				(arc
					(start 0.6096 0)
					(mid -0.6096 0)
					(end 0.6096 0)
				)
			)
			(stroke
				(width 0)
				(type default)
			)
			(fill no)
			(layer "F.Fab")
		)
		(pad "1" smd circle
			(at 0 0)
			(size 0.7112 0.7112)
			(layers "F.Cu" "F.Mask" "F.Paste")
			(net "TP_BMC_GPIOL1")
		)
	)
	(footprint ""
		(layer "F.Cu")
		(at 74.0918 -185.9026)
		(property "Reference" "R507"
			(at 0 0 0)
			(layer "F.SilkS")
			(hide yes)
			(effects
				(font
					(size 1.27 1.27)
				)
			)
		)
		(property "Value" "10KR2F-2-GP"
			(at 0.064008 -3.993896 0)
			(unlocked yes)
			(layer "F.Fab")
			(hide yes)
			(effects
				(font
					(size 1.016 1.016)
					(thickness 0.1524)
				)
			)
		)
		(property "Device Type" "R402H16"
			(at 0.064008 -5.517896 0)
			(unlocked yes)
			(layer "F.Fab")
			(hide yes)
			(effects
				(font
					(size 1.016 1.016)
					(thickness 0.1524)
				)
			)
		)
		(duplicate_pad_numbers_are_jumpers no)
		(fp_line
			(start -0.508 -0.9398)
			(end -0.508 0.9398)
			(stroke
				(width 0.1524)
				(type default)
			)
			(layer "F.SilkS")
		)
		(fp_line
			(start 0.508 -0.9398)
			(end -0.508 -0.9398)
			(stroke
				(width 0.1524)
				(type default)
			)
			(layer "F.SilkS")
		)
		(fp_rect
			(start -0.508 0.9398)
			(end 0.508 -0.9398)
			(stroke
				(width 0)
				(type default)
			)
			(fill no)
			(layer "F.CrtYd")
		)
		(fp_rect
			(start -0.508 0.9398)
			(end 0.508 -0.9398)
			(stroke
				(width 0)
				(type default)
			)
			(fill no)
			(layer "F.Fab")
		)
		(pad "1" smd custom
			(at 0 -0.4445)
			(size 0.1397 0.1397)
			(layers "F.Cu" "F.Mask" "F.Paste")
			(net "P3V3_STBY")
			(options
				(clearance outline)
				(anchor circle)
			)
			(primitives
				(gr_poly
					(pts
						(arc
							(start -0.1778 -0.2794)
							(mid -0.249642 -0.249642)
							(end -0.2794 -0.1778)
						)
						(arc
							(start -0.2794 0.1778)
							(mid -0.249642 0.249642)
							(end -0.1778 0.2794)
						)
						(arc
							(start 0.1778 0.2794)
							(mid 0.249642 0.249642)
							(end 0.2794 0.1778)
						)
						(arc
							(start 0.2794 -0.1778)
							(mid 0.249642 -0.249642)
							(end 0.1778 -0.2794)
						)
					)
					(width 0)
					(fill yes)
				)
			)
		)
		(pad "2" smd custom
			(at 0 0.4445)
			(size 0.1397 0.1397)
			(layers "F.Cu" "F.Mask" "F.Paste")
			(net "PWRGD_P2V5_STBY")
			(options
				(clearance outline)
				(anchor circle)
			)
			(primitives
				(gr_poly
					(pts
						(arc
							(start -0.1778 -0.2794)
							(mid -0.249642 -0.249642)
							(end -0.2794 -0.1778)
						)
						(arc
							(start -0.2794 0.1778)
							(mid -0.249642 0.249642)
							(end -0.1778 0.2794)
						)
						(arc
							(start 0.1778 0.2794)
							(mid 0.249642 0.249642)
							(end 0.2794 0.1778)
						)
						(arc
							(start 0.2794 -0.1778)
							(mid 0.249642 -0.249642)
							(end 0.1778 -0.2794)
						)
					)
					(width 0)
					(fill yes)
				)
			)
		)
	)
	(footprint ""
		(layer "F.Cu")
		(at 21.6916 -161.725864)
		(property "Reference" "C227"
			(at 0 0 0)
			(layer "F.SilkS")
			(hide yes)
			(effects
				(font
					(size 1.27 1.27)
				)
			)
		)
		(property "Value" "SCD1U16V2KX-3GP"
			(at 1.1811 -2.7051 0)
			(unlocked yes)
			(layer "F.Fab")
			(hide yes)
			(effects
				(font
					(size 1.016 1.016)
					(thickness 0.1524)
				)
			)
		)
		(property "Device Type" "C402H22"
			(at 1.1811 -4.2291 0)
			(unlocked yes)
			(layer "F.Fab")
			(hide yes)
			(effects
				(font
					(size 1.016 1.016)
					(thickness 0.1524)
				)
			)
		)
		(duplicate_pad_numbers_are_jumpers no)
		(fp_rect
			(start -0.4318 0.9525)
			(end 0.4318 -0.9525)
			(stroke
				(width 0)
				(type default)
			)
			(fill no)
			(layer "F.CrtYd")
		)
		(fp_rect
			(start -0.4318 0.9525)
			(end 0.4318 -0.9525)
			(stroke
				(width 0)
				(type default)
			)
			(fill no)
			(layer "F.Fab")
		)
		(pad "1" smd custom
			(at 0 -0.4445)
			(size 0.1524 0.1524)
			(layers "F.Cu" "F.Mask" "F.Paste")
			(net "TPS74801_P1V2_STBY_OUT")
			(options
				(clearance outline)
				(anchor circle)
			)
			(primitives
				(gr_poly
					(pts
						(arc
							(start 0.3048 -0.2032)
							(mid 0.275042 -0.275042)
							(end 0.2032 -0.3048)
						)
						(arc
							(start -0.2032 -0.3048)
							(mid -0.275042 -0.275042)
							(end -0.3048 -0.2032)
						)
						(arc
							(start -0.3048 0.2032)
							(mid -0.275042 0.275042)
							(end -0.2032 0.3048)
						)
						(arc
							(start 0.2032 0.3048)
							(mid 0.275042 0.275042)
							(end 0.3048 0.2032)
						)
					)
					(width 0)
					(fill yes)
				)
			)
		)
		(pad "2" smd custom
			(at 0 0.4445)
			(size 0.1524 0.1524)
			(layers "F.Cu" "F.Mask" "F.Paste")
			(net "GND")
			(options
				(clearance outline)
				(anchor circle)
			)
			(primitives
				(gr_poly
					(pts
						(arc
							(start 0.3048 -0.2032)
							(mid 0.275042 -0.275042)
							(end 0.2032 -0.3048)
						)
						(arc
							(start -0.2032 -0.3048)
							(mid -0.275042 -0.275042)
							(end -0.3048 -0.2032)
						)
						(arc
							(start -0.3048 0.2032)
							(mid -0.275042 0.275042)
							(end -0.2032 0.3048)
						)
						(arc
							(start 0.2032 0.3048)
							(mid 0.275042 0.275042)
							(end 0.3048 0.2032)
						)
					)
					(width 0)
					(fill yes)
				)
			)
		)
	)
	(footprint ""
		(layer "F.Cu")
		(at 70.5104 -170.2054)
		(property "Reference" "D11"
			(at 0 0 0)
			(layer "F.SilkS")
			(hide yes)
			(effects
				(font
					(size 1.27 1.27)
				)
			)
		)
		(property "Value" "BAT54WS-7-F-GP"
			(at 0 -6.7818 0)
			(unlocked yes)
			(layer "F.Fab")
			(hide yes)
			(effects
				(font
					(size 1.016 1.016)
					(thickness 0.1524)
				)
			)
		)
		(property "Device Type" "SOD323AKH42"
			(at 0 -8.6868 0)
			(unlocked yes)
			(layer "F.Fab")
			(hide yes)
			(effects
				(font
					(size 1.016 1.016)
					(thickness 0.1524)
				)
			)
		)
		(duplicate_pad_numbers_are_jumpers no)
		(fp_line
			(start -0.889 -1.9304)
			(end 0.889 -1.9304)
			(stroke
				(width 0.1524)
				(type default)
			)
			(layer "F.SilkS")
		)
		(fp_line
			(start -0.889 2.159)
			(end -0.889 -1.9304)
			(stroke
				(width 0.1524)
				(type default)
			)
			(layer "F.SilkS")
		)
		(fp_line
			(start 0.762 2.0574)
			(end -0.762 2.0574)
			(stroke
				(width 0.508)
				(type default)
			)
			(layer "F.SilkS")
		)
		(fp_line
			(start 0.889 -1.9304)
			(end 0.889 2.159)
			(stroke
				(width 0.1524)
				(type default)
			)
			(layer "F.SilkS")
		)
		(fp_line
			(start 0.889 2.159)
			(end -0.889 2.159)
			(stroke
				(width 0.1524)
				(type default)
			)
			(layer "F.SilkS")
		)
		(fp_rect
			(start -1.016 2.3114)
			(end 1.016 -2.0066)
			(stroke
				(width 0)
				(type default)
			)
			(fill no)
			(layer "F.CrtYd")
		)
		(fp_poly
			(pts
				(xy -1.016 -2.0066) (xy 1.016 -2.0066) (xy 1.016 2.3114) (xy -1.016 2.3114)
			)
			(stroke
				(width 0)
				(type default)
			)
			(fill no)
			(layer "F.Fab")
		)
		(pad "A" smd rect
			(at 0 -1.143)
			(size 0.5588 1.016)
			(layers "F.Cu" "F.Mask" "F.Paste")
			(net "BMC_SELF_HW_RST")
		)
		(pad "K" smd rect
			(at 0 1.143)
			(size 0.5588 1.016)
			(layers "F.Cu" "F.Mask" "F.Paste")
			(net "BMC_SELF_HW_RST_D")
		)
	)
)
